# S9S_MB_2U (Grand Teton) — schematic netlist excerpt (pin names and nets, part order shuffled) for the footprints in the layout excerpt that follows; sources: Cadence DE-HDL packaged netlist, KiCad conversion of 03242023_DA0F0TMBIJ0_F0T_Motherboard_J_brd_V01_OCP.brd

PC2201  Q_CAP  0.068UF 16V 10% EMPTY  pkg 0402  page 193 : A = P3V3_E1S_DVDT_0 ; B = GND
PR292  Q_RES  8.87K 1% EMPTY  pkg 0402LF  page 287 : A = PVCCIN_CPU1_LSET5 ; B = GND

(kicad_pcb
	(version 20260206)
	(generator "pcbnew")
	(generator_version "10.0")
	(general
		(thickness 1.6)
		(legacy_teardrops no)
	)
	(paper "A4")
	(title_block
		(title "03242023_DA0F0TMBIJ0_F0T_Motherboard_J_brd_V01_OCP.brd")
		(comment 1 "Grand Teton / footprints 1979-1980 of 6105")
	)
	(layers
		(0 "F.Cu" signal "TOP")
		(4 "In1.Cu" signal "GND")
		(6 "In2.Cu" signal "IN1")
		(8 "In3.Cu" signal "GND1")
		(10 "In4.Cu" signal "IN2")
		(12 "In5.Cu" signal "GND2")
		(14 "In6.Cu" signal "IN3")
		(16 "In7.Cu" signal "GND3")
		(18 "In8.Cu" signal "VCC")
		(20 "In9.Cu" signal "VCC1")
		(22 "In10.Cu" signal "GND4")
		(24 "In11.Cu" signal "IN4")
		(26 "In12.Cu" signal "GND5")
		(28 "In13.Cu" signal "IN5")
		(30 "In14.Cu" signal "GND6")
		(32 "In15.Cu" signal "IN6")
		(34 "In16.Cu" signal "GND7")
		(2 "B.Cu" signal "BOTTOM")
		(9 "F.Adhes" user "F.Adhesive")
		(11 "B.Adhes" user "B.Adhesive")
		(13 "F.Paste" user "Package Geometry/Pastemask Top")
		(15 "B.Paste" user "Package Geometry/Pastemask Bottom")
		(5 "F.SilkS" user "Ref Des/Silkscreen Top")
		(7 "B.SilkS" user "Ref Des/Silkscreen Bottom")
		(1 "F.Mask" user "Board Geometry/Soldermask Top")
		(3 "B.Mask" user "Board Geometry/Soldermask Bottom")
		(17 "Dwgs.User" user "User.Drawings")
		(19 "Cmts.User" user "User.Comments")
		(21 "Eco1.User" user "User.Eco1")
		(23 "Eco2.User" user "User.Eco2")
		(25 "Edge.Cuts" user "Board Geometry/Outline")
		(27 "Margin" user)
		(31 "F.CrtYd" user "Package Geometry/Place Bound Top")
		(29 "B.CrtYd" user "Package Geometry/Place Bound Bottom")
		(35 "F.Fab" user "Ref Des/Assembly Top")
		(33 "B.Fab" user "Ref Des/Assembly Bottom")
	)
	(footprint ""
		(layer "F.Cu")
		(at 198.41464 -71.582788)
		(property "Reference" "PC2201"
			(at 0 0 0)
			(layer "F.SilkS")
			(hide yes)
			(effects
				(font
					(size 1.27 1.27)
				)
			)
		)
		(property "Value" ""
			(at 0 0 0)
			(layer "F.Fab")
			(effects
				(font
					(size 1.27 1.27)
				)
			)
		)
		(duplicate_pad_numbers_are_jumpers no)
		(fp_line
			(start -0.7874 -0.4064)
			(end 0.7874 -0.4064)
			(stroke
				(width 0.1524)
				(type default)
			)
			(layer "F.SilkS")
		)
		(fp_line
			(start -0.7874 0.4064)
			(end -0.7874 -0.4064)
			(stroke
				(width 0.1524)
				(type default)
			)
			(layer "F.SilkS")
		)
		(fp_line
			(start 0.7874 -0.4064)
			(end 0.7874 0.4064)
			(stroke
				(width 0.1524)
				(type default)
			)
			(layer "F.SilkS")
		)
		(fp_line
			(start 0.7874 0.4064)
			(end -0.7874 0.4064)
			(stroke
				(width 0.1524)
				(type default)
			)
			(layer "F.SilkS")
		)
		(fp_line
			(start -0.67945 -0.305054)
			(end -0.12065 -0.305054)
			(stroke
				(width 0.1)
				(type default)
			)
			(layer "F.Fab")
		)
		(fp_line
			(start -0.67945 0.3048)
			(end -0.67945 -0.305054)
			(stroke
				(width 0.1)
				(type default)
			)
			(layer "F.Fab")
		)
		(fp_line
			(start -0.12065 -0.305054)
			(end -0.12065 -0.2794)
			(stroke
				(width 0.1)
				(type default)
			)
			(layer "F.Fab")
		)
		(fp_line
			(start -0.12065 -0.2794)
			(end 0.12065 -0.2794)
			(stroke
				(width 0.1)
				(type default)
			)
			(layer "F.Fab")
		)
		(fp_line
			(start -0.12065 0.2794)
			(end -0.12065 0.3048)
			(stroke
				(width 0.1)
				(type default)
			)
			(layer "F.Fab")
		)
		(fp_line
			(start -0.12065 0.3048)
			(end -0.67945 0.3048)
			(stroke
				(width 0.1)
				(type default)
			)
			(layer "F.Fab")
		)
		(fp_line
			(start 0.120396 0.2794)
			(end -0.12065 0.2794)
			(stroke
				(width 0.1)
				(type default)
			)
			(layer "F.Fab")
		)
		(fp_line
			(start 0.120396 0.3048)
			(end 0.120396 0.2794)
			(stroke
				(width 0.1)
				(type default)
			)
			(layer "F.Fab")
		)
		(fp_line
			(start 0.12065 -0.3048)
			(end 0.67945 -0.3048)
			(stroke
				(width 0.1)
				(type default)
			)
			(layer "F.Fab")
		)
		(fp_line
			(start 0.12065 -0.2794)
			(end 0.12065 -0.3048)
			(stroke
				(width 0.1)
				(type default)
			)
			(layer "F.Fab")
		)
		(fp_line
			(start 0.67945 -0.3048)
			(end 0.67945 0.3048)
			(stroke
				(width 0.1)
				(type default)
			)
			(layer "F.Fab")
		)
		(fp_line
			(start 0.67945 0.3048)
			(end 0.120396 0.3048)
			(stroke
				(width 0.1)
				(type default)
			)
			(layer "F.Fab")
		)
		(pad "1" smd circle
			(at -0.40005 0)
			(size 0 0)
			(layers "F.Cu" "F.Mask" "F.Paste")
			(net "P3V3_E1S_DVDT_0")
		)
		(pad "2" smd circle
			(at 0.40005 0)
			(size 0 0)
			(layers "F.Cu" "F.Mask" "F.Paste")
			(net "GND")
		)
	)
	(footprint ""
		(layer "F.Cu")
		(at 128.348486 -342.270334)
		(property "Reference" "PR292"
			(at 0 0 0)
			(layer "F.SilkS")
			(hide yes)
			(effects
				(font
					(size 1.27 1.27)
				)
			)
		)
		(property "Value" ""
			(at 0 0 0)
			(layer "F.Fab")
			(effects
				(font
					(size 1.27 1.27)
				)
			)
		)
		(duplicate_pad_numbers_are_jumpers no)
		(fp_line
			(start -0.7874 -0.4064)
			(end 0.7874 -0.4064)
			(stroke
				(width 0.1524)
				(type default)
			)
			(layer "F.SilkS")
		)
		(fp_line
			(start -0.7874 0.4064)
			(end -0.7874 -0.4064)
			(stroke
				(width 0.1524)
				(type default)
			)
			(layer "F.SilkS")
		)
		(fp_line
			(start 0.7874 -0.4064)
			(end 0.7874 0.4064)
			(stroke
				(width 0.1524)
				(type default)
			)
			(layer "F.SilkS")
		)
		(fp_line
			(start 0.7874 0.4064)
			(end -0.7874 0.4064)
			(stroke
				(width 0.1524)
				(type default)
			)
			(layer "F.SilkS")
		)
		(fp_line
			(start -0.67945 -0.305054)
			(end -0.12065 -0.305054)
			(stroke
				(width 0.1)
				(type default)
			)
			(layer "F.Fab")
		)
		(fp_line
			(start -0.67945 0.3048)
			(end -0.67945 -0.305054)
			(stroke
				(width 0.1)
				(type default)
			)
			(layer "F.Fab")
		)
		(fp_line
			(start -0.12065 -0.305054)
			(end -0.12065 -0.2794)
			(stroke
				(width 0.1)
				(type default)
			)
			(layer "F.Fab")
		)
		(fp_line
			(start -0.12065 -0.2794)
			(end 0.12065 -0.2794)
			(stroke
				(width 0.1)
				(type default)
			)
			(layer "F.Fab")
		)
		(fp_line
			(start -0.12065 0.2794)
			(end -0.12065 0.3048)
			(stroke
				(width 0.1)
				(type default)
			)
			(layer "F.Fab")
		)
		(fp_line
			(start -0.12065 0.3048)
			(end -0.67945 0.3048)
			(stroke
				(width 0.1)
				(type default)
			)
			(layer "F.Fab")
		)
		(fp_line
			(start 0.120396 0.2794)
			(end -0.12065 0.2794)
			(stroke
				(width 0.1)
				(type default)
			)
			(layer "F.Fab")
		)
		(fp_line
			(start 0.120396 0.3048)
			(end 0.120396 0.2794)
			(stroke
				(width 0.1)
				(type default)
			)
			(layer "F.Fab")
		)
		(fp_line
			(start 0.12065 -0.3048)
			(end 0.67945 -0.3048)
			(stroke
				(width 0.1)
				(type default)
			)
			(layer "F.Fab")
		)
		(fp_line
			(start 0.12065 -0.2794)
			(end 0.12065 -0.3048)
			(stroke
				(width 0.1)
				(type default)
			)
			(layer "F.Fab")
		)
		(fp_line
			(start 0.67945 -0.3048)
			(end 0.67945 0.3048)
			(stroke
				(width 0.1)
				(type default)
			)
			(layer "F.Fab")
		)
		(fp_line
			(start 0.67945 0.3048)
			(end 0.120396 0.3048)
			(stroke
				(width 0.1)
				(type default)
			)
			(layer "F.Fab")
		)
		(pad "1" smd circle
			(at -0.40005 0)
			(size 0 0)
			(layers "F.Cu" "F.Mask" "F.Paste")
			(net "PVCCIN_CPU1_LSET5")
		)
		(pad "2" smd circle
			(at 0.40005 0)
			(size 0 0)
			(layers "F.Cu" "F.Mask" "F.Paste")
			(net "GND")
		)
	)
)
